(kicad_pcb
	(version 20260206)
	(generator "pcbnew")
	(generator_version "10.0")
	(general
		(thickness 1.6)
		(legacy_teardrops no)
	)
	(paper "A4")
	(title_block
		(title "baseboard — 13948-1b.1110WZS1818.brd")
		(comment 1 "Honey Badger (Wiwynn) / footprints 1847-1854 of 2523")
	)
	(layers
		(0 "F.Cu" signal "TOP")
		(4 "In1.Cu" signal "L2GND")
		(6 "In2.Cu" signal "L3")
		(8 "In3.Cu" signal "L4VCC")
		(10 "In4.Cu" signal "L5VCC")
		(12 "In5.Cu" signal "L6")
		(14 "In6.Cu" signal "L7GND")
		(2 "B.Cu" signal "BOTTOM")
		(9 "F.Adhes" user "F.Adhesive")
		(11 "B.Adhes" user "B.Adhesive")
		(13 "F.Paste" user "Package Geometry/Pastemask Top")
		(15 "B.Paste" user "Package Geometry/Pastemask Bottom")
		(5 "F.SilkS" user "Ref Des/Silkscreen Top")
		(7 "B.SilkS" user "Ref Des/Silkscreen Bottom")
		(1 "F.Mask" user "Board Geometry/Soldermask Top")
		(3 "B.Mask" user "Board Geometry/Soldermask Bottom")
		(17 "Dwgs.User" user "User.Drawings")
		(19 "Cmts.User" user "User.Comments")
		(21 "Eco1.User" user "User.Eco1")
		(23 "Eco2.User" user "User.Eco2")
		(25 "Edge.Cuts" user "Board Geometry/Outline")
		(27 "Margin" user)
		(31 "F.CrtYd" user "Package Geometry/Place Bound Top")
		(29 "B.CrtYd" user "Package Geometry/Place Bound Bottom")
		(35 "F.Fab" user "Ref Des/Assembly Top")
		(33 "B.Fab" user "Ref Des/Assembly Bottom")
	)
	(footprint ""
		(layer "B.Cu")
		(at 317.5 -182.753 -90)
		(property "Reference" "R3099"
			(at 0 0 90)
			(layer "B.SilkS")
			(hide yes)
			(effects
				(font
					(size 1.27 1.27)
				)
				(justify mirror)
			)
		)
		(property "Value" "1KR2F-3-GP"
			(at -0.064008 -3.993896 270)
			(unlocked yes)
			(layer "B.Fab")
			(hide yes)
			(effects
				(font
					(size 1.016 1.016)
					(thickness 0.1524)
				)
				(justify mirror)
			)
		)
		(property "Device Type" "R402H16"
			(at -0.064008 -5.517896 270)
			(unlocked yes)
			(layer "B.Fab")
			(hide yes)
			(effects
				(font
					(size 1.016 1.016)
					(thickness 0.1524)
				)
				(justify mirror)
			)
		)
		(duplicate_pad_numbers_are_jumpers no)
		(fp_line
			(start -0.508 -0.9398)
			(end 0.508 -0.9398)
			(stroke
				(width 0.1524)
				(type default)
			)
			(layer "B.SilkS")
		)
		(fp_line
			(start 0.508 -0.9398)
			(end 0.508 0.9398)
			(stroke
				(width 0.1524)
				(type default)
			)
			(layer "B.SilkS")
		)
		(fp_rect
			(start 0.508 0.9398)
			(end -0.508 -0.9398)
			(stroke
				(width 0)
				(type default)
			)
			(fill no)
			(layer "B.CrtYd")
		)
		(fp_rect
			(start 0.508 0.9398)
			(end -0.508 -0.9398)
			(stroke
				(width 0)
				(type default)
			)
			(fill no)
			(layer "B.Fab")
		)
		(pad "1" smd custom
			(at 0 -0.4445 90)
			(size 0.1397 0.1397)
			(layers "B.Cu" "B.Mask" "B.Paste")
			(net "ADC_P1V5_E")
			(options
				(clearance outline)
				(anchor circle)
			)
			(primitives
				(gr_poly
					(pts
						(arc
							(start -0.1778 0.2794)
							(mid -0.249642 0.249642)
							(end -0.2794 0.1778)
						)
						(arc
							(start -0.2794 -0.1778)
							(mid -0.249642 -0.249642)
							(end -0.1778 -0.2794)
						)
						(arc
							(start 0.1778 -0.2794)
							(mid 0.249642 -0.249642)
							(end 0.2794 -0.1778)
						)
						(arc
							(start 0.2794 0.1778)
							(mid 0.249642 0.249642)
							(end 0.1778 0.2794)
						)
					)
					(width 0)
					(fill yes)
				)
			)
		)
		(pad "2" smd custom
			(at 0 0.4445 90)
			(size 0.1397 0.1397)
			(layers "B.Cu" "B.Mask" "B.Paste")
			(net "GND")
			(options
				(clearance outline)
				(anchor circle)
			)
			(primitives
				(gr_poly
					(pts
						(arc
							(start -0.1778 0.2794)
							(mid -0.249642 0.249642)
							(end -0.2794 0.1778)
						)
						(arc
							(start -0.2794 -0.1778)
							(mid -0.249642 -0.249642)
							(end -0.1778 -0.2794)
						)
						(arc
							(start 0.1778 -0.2794)
							(mid 0.249642 -0.249642)
							(end 0.2794 -0.1778)
						)
						(arc
							(start 0.2794 0.1778)
							(mid 0.249642 0.249642)
							(end 0.1778 0.2794)
						)
					)
					(width 0)
					(fill yes)
				)
			)
		)
	)
	(footprint ""
		(layer "B.Cu")
		(at 324.358 -179.705 180)
		(property "Reference" "C8087"
			(at 0 0 0)
			(layer "B.SilkS")
			(hide yes)
			(effects
				(font
					(size 1.27 1.27)
				)
				(justify mirror)
			)
		)
		(property "Value" "SCD1U25V2KX-2-GP"
			(at -1.1811 -2.7051 180)
			(unlocked yes)
			(layer "B.Fab")
			(hide yes)
			(effects
				(font
					(size 1.016 1.016)
					(thickness 0.1524)
				)
				(justify mirror)
			)
		)
		(property "Device Type" "C402H22"
			(at -1.1811 -4.2291 180)
			(unlocked yes)
			(layer "B.Fab")
			(hide yes)
			(effects
				(font
					(size 1.016 1.016)
					(thickness 0.1524)
				)
				(justify mirror)
			)
		)
		(duplicate_pad_numbers_are_jumpers no)
		(fp_rect
			(start 0.4318 0.9525)
			(end -0.4318 -0.9525)
			(stroke
				(width 0)
				(type default)
			)
			(fill no)
			(layer "B.CrtYd")
		)
		(fp_rect
			(start 0.4318 0.9525)
			(end -0.4318 -0.9525)
			(stroke
				(width 0)
				(type default)
			)
			(fill no)
			(layer "B.Fab")
		)
		(pad "1" smd custom
			(at 0 -0.4445)
			(size 0.1524 0.1524)
			(layers "B.Cu" "B.Mask" "B.Paste")
			(net "ADC_P3V3_STBY")
			(options
				(clearance outline)
				(anchor circle)
			)
			(primitives
				(gr_poly
					(pts
						(arc
							(start 0.3048 0.2032)
							(mid 0.275042 0.275042)
							(end 0.2032 0.3048)
						)
						(arc
							(start -0.2032 0.3048)
							(mid -0.275042 0.275042)
							(end -0.3048 0.2032)
						)
						(arc
							(start -0.3048 -0.2032)
							(mid -0.275042 -0.275042)
							(end -0.2032 -0.3048)
						)
						(arc
							(start 0.2032 -0.3048)
							(mid 0.275042 -0.275042)
							(end 0.3048 -0.2032)
						)
					)
					(width 0)
					(fill yes)
				)
			)
		)
		(pad "2" smd custom
			(at 0 0.4445)
			(size 0.1524 0.1524)
			(layers "B.Cu" "B.Mask" "B.Paste")
			(net "GND")
			(options
				(clearance outline)
				(anchor circle)
			)
			(primitives
				(gr_poly
					(pts
						(arc
							(start 0.3048 0.2032)
							(mid 0.275042 0.275042)
							(end 0.2032 0.3048)
						)
						(arc
							(start -0.2032 0.3048)
							(mid -0.275042 0.275042)
							(end -0.3048 0.2032)
						)
						(arc
							(start -0.3048 -0.2032)
							(mid -0.275042 -0.275042)
							(end -0.2032 -0.3048)
						)
						(arc
							(start 0.2032 -0.3048)
							(mid 0.275042 -0.275042)
							(end 0.3048 -0.2032)
						)
					)
					(width 0)
					(fill yes)
				)
			)
		)
	)
	(footprint ""
		(layer "B.Cu")
		(at 101.480366 -41.91 -90)
		(property "Reference" "SC1027"
			(at 0 0 90)
			(layer "B.SilkS")
			(hide yes)
			(effects
				(font
					(size 1.27 1.27)
				)
				(justify mirror)
			)
		)
		(property "Value" "SC1U10V2KX-4-GP"
			(at -1.1811 -2.7051 270)
			(unlocked yes)
			(layer "B.Fab")
			(hide yes)
			(effects
				(font
					(size 1.016 1.016)
					(thickness 0.1524)
				)
				(justify mirror)
			)
		)
		(property "Device Type" "C402H22"
			(at -1.1811 -4.2291 270)
			(unlocked yes)
			(layer "B.Fab")
			(hide yes)
			(effects
				(font
					(size 1.016 1.016)
					(thickness 0.1524)
				)
				(justify mirror)
			)
		)
		(duplicate_pad_numbers_are_jumpers no)
		(fp_rect
			(start 0.4318 0.9525)
			(end -0.4318 -0.9525)
			(stroke
				(width 0)
				(type default)
			)
			(fill no)
			(layer "B.CrtYd")
		)
		(fp_rect
			(start 0.4318 0.9525)
			(end -0.4318 -0.9525)
			(stroke
				(width 0)
				(type default)
			)
			(fill no)
			(layer "B.Fab")
		)
		(pad "1" smd custom
			(at 0 -0.4445 90)
			(size 0.1524 0.1524)
			(layers "B.Cu" "B.Mask" "B.Paste")
			(net "P0V955_C")
			(options
				(clearance outline)
				(anchor circle)
			)
			(primitives
				(gr_poly
					(pts
						(arc
							(start 0.3048 0.2032)
							(mid 0.275042 0.275042)
							(end 0.2032 0.3048)
						)
						(arc
							(start -0.2032 0.3048)
							(mid -0.275042 0.275042)
							(end -0.3048 0.2032)
						)
						(arc
							(start -0.3048 -0.2032)
							(mid -0.275042 -0.275042)
							(end -0.2032 -0.3048)
						)
						(arc
							(start 0.2032 -0.3048)
							(mid 0.275042 -0.275042)
							(end 0.3048 -0.2032)
						)
					)
					(width 0)
					(fill yes)
				)
			)
		)
		(pad "2" smd custom
			(at 0 0.4445 90)
			(size 0.1524 0.1524)
			(layers "B.Cu" "B.Mask" "B.Paste")
			(net "GND")
			(options
				(clearance outline)
				(anchor circle)
			)
			(primitives
				(gr_poly
					(pts
						(arc
							(start 0.3048 0.2032)
							(mid 0.275042 0.275042)
							(end 0.2032 0.3048)
						)
						(arc
							(start -0.2032 0.3048)
							(mid -0.275042 0.275042)
							(end -0.3048 0.2032)
						)
						(arc
							(start -0.3048 -0.2032)
							(mid -0.275042 -0.275042)
							(end -0.2032 -0.3048)
						)
						(arc
							(start 0.2032 -0.3048)
							(mid 0.275042 -0.275042)
							(end 0.3048 -0.2032)
						)
					)
					(width 0)
					(fill yes)
				)
			)
		)
	)
	(footprint ""
		(layer "B.Cu")
		(at 163.957 -117.475)
		(property "Reference" "SQ12"
			(at 0 0 0)
			(layer "B.SilkS")
			(hide yes)
			(effects
				(font
					(size 1.27 1.27)
				)
				(justify mirror)
			)
		)
		(property "Value" "2N7002A-7-GP"
			(at -0.127 -8.9662 0)
			(unlocked yes)
			(layer "B.Fab")
			(hide yes)
			(effects
				(font
					(size 1.016 1.016)
					(thickness 0.1524)
				)
				(justify mirror)
			)
		)
		(property "Device Type" "SOT23DGS2D4H48"
			(at -0.127 -10.4902 0)
			(unlocked yes)
			(layer "B.Fab")
			(hide yes)
			(effects
				(font
					(size 1.016 1.016)
					(thickness 0.1524)
				)
				(justify mirror)
			)
		)
		(duplicate_pad_numbers_are_jumpers no)
		(fp_line
			(start -1.651 -1.778)
			(end 1.651 -1.778)
			(stroke
				(width 0.1524)
				(type default)
			)
			(layer "B.SilkS")
		)
		(fp_line
			(start -1.651 1.778)
			(end -1.651 -1.778)
			(stroke
				(width 0.1524)
				(type default)
			)
			(layer "B.SilkS")
		)
		(fp_line
			(start 1.651 -1.778)
			(end 1.651 1.778)
			(stroke
				(width 0.1524)
				(type default)
			)
			(layer "B.SilkS")
		)
		(fp_line
			(start 1.651 1.778)
			(end -1.651 1.778)
			(stroke
				(width 0.1524)
				(type default)
			)
			(layer "B.SilkS")
		)
		(fp_poly
			(pts
				(xy 1.778 1.8796) (xy 1.778 -1.8796) (xy -1.778 -1.8796) (xy -1.778 1.8796)
			)
			(stroke
				(width 0)
				(type default)
			)
			(fill no)
			(layer "B.CrtYd")
		)
		(fp_poly
			(pts
				(xy 1.778 1.8796) (xy 1.778 -1.8796) (xy -1.778 -1.8796) (xy -1.778 1.8796)
			)
			(stroke
				(width 0)
				(type default)
			)
			(fill no)
			(layer "B.Fab")
		)
		(pad "D" smd custom
			(at 0 -0.9525 180)
			(size 0.1905 0.1905)
			(layers "B.Cu" "B.Mask" "B.Paste")
			(net "EXP_RST")
			(options
				(clearance outline)
				(anchor circle)
			)
			(primitives
				(gr_poly
					(pts
						(arc
							(start -0.1778 -0.5715)
							(mid -0.321484 -0.511984)
							(end -0.381 -0.3683)
						)
						(arc
							(start -0.381 0.3683)
							(mid -0.321484 0.511984)
							(end -0.1778 0.5715)
						)
						(arc
							(start 0.1778 0.5715)
							(mid 0.321484 0.511984)
							(end 0.381 0.3683)
						)
						(arc
							(start 0.381 -0.3683)
							(mid 0.321484 -0.511984)
							(end 0.1778 -0.5715)
						)
					)
					(width 0)
					(fill yes)
				)
			)
		)
		(pad "G" smd custom
			(at 0.98425 0.9525 180)
			(size 0.1905 0.1905)
			(layers "B.Cu" "B.Mask" "B.Paste")
			(net "P3V3_STBY_G4")
			(options
				(clearance outline)
				(anchor circle)
			)
			(primitives
				(gr_poly
					(pts
						(arc
							(start -0.1778 -0.5715)
							(mid -0.321484 -0.511984)
							(end -0.381 -0.3683)
						)
						(arc
							(start -0.381 0.3683)
							(mid -0.321484 0.511984)
							(end -0.1778 0.5715)
						)
						(arc
							(start 0.1778 0.5715)
							(mid 0.321484 0.511984)
							(end 0.381 0.3683)
						)
						(arc
							(start 0.381 -0.3683)
							(mid 0.321484 -0.511984)
							(end 0.1778 -0.5715)
						)
					)
					(width 0)
					(fill yes)
				)
			)
		)
		(pad "S" smd custom
			(at -0.98425 0.9525 180)
			(size 0.1905 0.1905)
			(layers "B.Cu" "B.Mask" "B.Paste")
			(net "GND")
			(options
				(clearance outline)
				(anchor circle)
			)
			(primitives
				(gr_poly
					(pts
						(arc
							(start -0.1778 -0.5715)
							(mid -0.321484 -0.511984)
							(end -0.381 -0.3683)
						)
						(arc
							(start -0.381 0.3683)
							(mid -0.321484 0.511984)
							(end -0.1778 0.5715)
						)
						(arc
							(start 0.1778 0.5715)
							(mid 0.321484 0.511984)
							(end 0.381 0.3683)
						)
						(arc
							(start 0.381 -0.3683)
							(mid 0.321484 -0.511984)
							(end 0.1778 -0.5715)
						)
					)
					(width 0)
					(fill yes)
				)
			)
		)
	)
	(footprint ""
		(layer "B.Cu")
		(at 123.298966 -45.466 90)
		(property "Reference" "SC974"
			(at 0 0 90)
			(layer "B.SilkS")
			(hide yes)
			(effects
				(font
					(size 1.27 1.27)
				)
				(justify mirror)
			)
		)
		(property "Value" "SCD1U16V2KX-3GP"
			(at -1.1811 -2.7051 90)
			(unlocked yes)
			(layer "B.Fab")
			(hide yes)
			(effects
				(font
					(size 1.016 1.016)
					(thickness 0.1524)
				)
				(justify mirror)
			)
		)
		(property "Device Type" "C402H22"
			(at -1.1811 -4.2291 90)
			(unlocked yes)
			(layer "B.Fab")
			(hide yes)
			(effects
				(font
					(size 1.016 1.016)
					(thickness 0.1524)
				)
				(justify mirror)
			)
		)
		(duplicate_pad_numbers_are_jumpers no)
		(fp_rect
			(start 0.4318 0.9525)
			(end -0.4318 -0.9525)
			(stroke
				(width 0)
				(type default)
			)
			(fill no)
			(layer "B.CrtYd")
		)
		(fp_rect
			(start 0.4318 0.9525)
			(end -0.4318 -0.9525)
			(stroke
				(width 0)
				(type default)
			)
			(fill no)
			(layer "B.Fab")
		)
		(pad "1" smd custom
			(at 0 -0.4445 270)
			(size 0.1524 0.1524)
			(layers "B.Cu" "B.Mask" "B.Paste")
			(net "P1V8_C")
			(options
				(clearance outline)
				(anchor circle)
			)
			(primitives
				(gr_poly
					(pts
						(arc
							(start 0.3048 0.2032)
							(mid 0.275042 0.275042)
							(end 0.2032 0.3048)
						)
						(arc
							(start -0.2032 0.3048)
							(mid -0.275042 0.275042)
							(end -0.3048 0.2032)
						)
						(arc
							(start -0.3048 -0.2032)
							(mid -0.275042 -0.275042)
							(end -0.2032 -0.3048)
						)
						(arc
							(start 0.2032 -0.3048)
							(mid 0.275042 -0.275042)
							(end 0.3048 -0.2032)
						)
					)
					(width 0)
					(fill yes)
				)
			)
		)
		(pad "2" smd custom
			(at 0 0.4445 270)
			(size 0.1524 0.1524)
			(layers "B.Cu" "B.Mask" "B.Paste")
			(net "GND")
			(options
				(clearance outline)
				(anchor circle)
			)
			(primitives
				(gr_poly
					(pts
						(arc
							(start 0.3048 0.2032)
							(mid 0.275042 0.275042)
							(end 0.2032 0.3048)
						)
						(arc
							(start -0.2032 0.3048)
							(mid -0.275042 0.275042)
							(end -0.3048 0.2032)
						)
						(arc
							(start -0.3048 -0.2032)
							(mid -0.275042 -0.275042)
							(end -0.2032 -0.3048)
						)
						(arc
							(start 0.2032 -0.3048)
							(mid 0.275042 -0.275042)
							(end 0.3048 -0.2032)
						)
					)
					(width 0)
					(fill yes)
				)
			)
		)
	)
	(footprint ""
		(layer "B.Cu")
		(at 116.85397 -102.616 -90)
		(property "Reference" "SC1169"
			(at 0 0 90)
			(layer "B.SilkS")
			(hide yes)
			(effects
				(font
					(size 1.27 1.27)
				)
				(justify mirror)
			)
		)
		(property "Value" "SCD1U6D3V1KX-GP"
			(at 2.8321 -1.7399 270)
			(unlocked yes)
			(layer "B.Fab")
			(hide yes)
			(effects
				(font
					(size 1.016 1.016)
					(thickness 0.1524)
				)
				(justify mirror)
			)
		)
		(property "Device Type" "C0201H13"
			(at 2.8321 -3.2639 270)
			(unlocked yes)
			(layer "B.Fab")
			(hide yes)
			(effects
				(font
					(size 1.016 1.016)
					(thickness 0.1524)
				)
				(justify mirror)
			)
		)
		(duplicate_pad_numbers_are_jumpers no)
		(fp_rect
			(start 0.2794 0.6477)
			(end -0.2794 -0.6477)
			(stroke
				(width 0)
				(type default)
			)
			(fill no)
			(layer "B.CrtYd")
		)
		(fp_rect
			(start 0.2794 0.6477)
			(end -0.2794 -0.6477)
			(stroke
				(width 0)
				(type default)
			)
			(fill no)
			(layer "B.Fab")
		)
		(pad "1" smd custom
			(at 0 -0.2794 90)
			(size 0.0762 0.0762)
			(layers "B.Cu" "B.Mask" "B.Paste")
			(net "GB_VDDA")
			(options
				(clearance outline)
				(anchor circle)
			)
			(primitives
				(gr_poly
					(pts
						(arc
							(start 0.1524 0.127)
							(mid 0.137521 0.162921)
							(end 0.1016 0.1778)
						)
						(arc
							(start -0.1016 0.1778)
							(mid -0.137521 0.162921)
							(end -0.1524 0.127)
						)
						(arc
							(start -0.1524 -0.127)
							(mid -0.137521 -0.162921)
							(end -0.1016 -0.1778)
						)
						(arc
							(start 0.1016 -0.1778)
							(mid 0.137521 -0.162921)
							(end 0.1524 -0.127)
						)
					)
					(width 0)
					(fill yes)
				)
			)
		)
		(pad "2" smd custom
			(at 0 0.2794 90)
			(size 0.0762 0.0762)
			(layers "B.Cu" "B.Mask" "B.Paste")
			(net "GND")
			(options
				(clearance outline)
				(anchor circle)
			)
			(primitives
				(gr_poly
					(pts
						(arc
							(start 0.1524 0.127)
							(mid 0.137521 0.162921)
							(end 0.1016 0.1778)
						)
						(arc
							(start -0.1016 0.1778)
							(mid -0.137521 0.162921)
							(end -0.1524 0.127)
						)
						(arc
							(start -0.1524 -0.127)
							(mid -0.137521 -0.162921)
							(end -0.1016 -0.1778)
						)
						(arc
							(start 0.1016 -0.1778)
							(mid 0.137521 -0.162921)
							(end 0.1524 -0.127)
						)
					)
					(width 0)
					(fill yes)
				)
			)
		)
	)
	(footprint ""
		(layer "B.Cu")
		(at 120.30837 -94.615 90)
		(property "Reference" "SC1142"
			(at 0 0 90)
			(layer "B.SilkS")
			(hide yes)
			(effects
				(font
					(size 1.27 1.27)
				)
				(justify mirror)
			)
		)
		(property "Value" "SCD1U6D3V1KX-GP"
			(at 2.8321 -1.7399 90)
			(unlocked yes)
			(layer "B.Fab")
			(hide yes)
			(effects
				(font
					(size 1.016 1.016)
					(thickness 0.1524)
				)
				(justify mirror)
			)
		)
		(property "Device Type" "C0201H13"
			(at 2.8321 -3.2639 90)
			(unlocked yes)
			(layer "B.Fab")
			(hide yes)
			(effects
				(font
					(size 1.016 1.016)
					(thickness 0.1524)
				)
				(justify mirror)
			)
		)
		(duplicate_pad_numbers_are_jumpers no)
		(fp_rect
			(start 0.2794 0.6477)
			(end -0.2794 -0.6477)
			(stroke
				(width 0)
				(type default)
			)
			(fill no)
			(layer "B.CrtYd")
		)
		(fp_rect
			(start 0.2794 0.6477)
			(end -0.2794 -0.6477)
			(stroke
				(width 0)
				(type default)
			)
			(fill no)
			(layer "B.Fab")
		)
		(pad "1" smd custom
			(at 0 -0.2794 270)
			(size 0.0762 0.0762)
			(layers "B.Cu" "B.Mask" "B.Paste")
			(net "GB_VDDH2")
			(options
				(clearance outline)
				(anchor circle)
			)
			(primitives
				(gr_poly
					(pts
						(arc
							(start 0.1524 0.127)
							(mid 0.137521 0.162921)
							(end 0.1016 0.1778)
						)
						(arc
							(start -0.1016 0.1778)
							(mid -0.137521 0.162921)
							(end -0.1524 0.127)
						)
						(arc
							(start -0.1524 -0.127)
							(mid -0.137521 -0.162921)
							(end -0.1016 -0.1778)
						)
						(arc
							(start 0.1016 -0.1778)
							(mid 0.137521 -0.162921)
							(end 0.1524 -0.127)
						)
					)
					(width 0)
					(fill yes)
				)
			)
		)
		(pad "2" smd custom
			(at 0 0.2794 270)
			(size 0.0762 0.0762)
			(layers "B.Cu" "B.Mask" "B.Paste")
			(net "GND")
			(options
				(clearance outline)
				(anchor circle)
			)
			(primitives
				(gr_poly
					(pts
						(arc
							(start 0.1524 0.127)
							(mid 0.137521 0.162921)
							(end 0.1016 0.1778)
						)
						(arc
							(start -0.1016 0.1778)
							(mid -0.137521 0.162921)
							(end -0.1524 0.127)
						)
						(arc
							(start -0.1524 -0.127)
							(mid -0.137521 -0.162921)
							(end -0.1016 -0.1778)
						)
						(arc
							(start 0.1016 -0.1778)
							(mid 0.137521 -0.162921)
							(end 0.1524 -0.127)
						)
					)
					(width 0)
					(fill yes)
				)
			)
		)
	)
	(footprint ""
		(layer "B.Cu")
		(at 349.749872 -54.99989)
		(property "Reference" ""
			(at 0 0 0)
			(layer "B.SilkS")
			(hide yes)
			(effects
				(font
					(size 1.27 1.27)
				)
				(justify mirror)
			)
		)
		(property "Value" "*"
			(at 5.5753 -0.4572 0)
			(unlocked yes)
			(layer "B.Fab")
			(hide yes)
			(effects
				(font
					(size 1.016 1.016)
					(thickness 0.1524)
				)
				(justify mirror)
			)
		)
		(duplicate_pad_numbers_are_jumpers no)
		(fp_poly
			(pts
				(arc
					(start 4.3053 0)
					(mid -4.3053 0)
					(end 4.3053 0)
				)
			)
			(stroke
				(width 0)
				(type default)
			)
			(fill no)
			(layer "B.CrtYd")
		)
		(fp_poly
			(pts
				(arc
					(start 4.3053 0)
					(mid -4.3053 0)
					(end 4.3053 0)
				)
			)
			(stroke
				(width 0)
				(type default)
			)
			(fill no)
			(layer "B.Fab")
		)
		(pad "1" smd custom
			(at 2.95275 0 180)
			(size 2.000013 2.000013)
			(layers "B.Cu" "B.Mask" "B.Paste")
			(net "Net_52")
			(options
				(clearance outline)
				(anchor circle)
			)
			(primitives
				(gr_poly
					(pts
						(arc
							(start 4.0005 -0.00254)
							(mid -4.000501 0)
							(end 4.0005 0.00254)
						)
						(arc
							(start 1.905 0.00254)
							(mid -1.905002 0)
							(end 1.905 -0.00254)
						)
					)
					(width 0)
					(fill yes)
				)
			)
		)
	)
)
